#ISCELL
  pure_quanta quanta_title_block_c *
  *
#ISCELL
  pure_quanta_power cad_note *
  *
#CELL
  pure_quanta genoa_sp5 *
  page48_i159
#ISCELL
  mstr_standard offpage *
  page48_i160
#ISCELL
  mstr_standard offpage *
  page48_i161
#ISCELL
  mstr_standard tap *
  page48_i162
#ISCELL
  mstr_standard tap *
  page48_i163
#ISCELL
  mstr_standard tap *
  page48_i164
#ISCELL
  mstr_standard tap *
  page48_i165
#ISCELL
  mstr_standard tap *
  page48_i166
#ISCELL
  mstr_standard tap *
  page48_i167
#ISCELL
  mstr_standard tap *
  page48_i168
#ISCELL
  mstr_standard tap *
  page48_i169
#ISCELL
  mstr_standard tap *
  page48_i170
#ISCELL
  mstr_standard tap *
  page48_i171
#ISCELL
  mstr_standard tap *
  page48_i172
#ISCELL
  mstr_standard tap *
  page48_i173
#ISCELL
  mstr_standard tap *
  page48_i174
#ISCELL
  mstr_standard tap *
  page48_i175
#ISCELL
  mstr_standard tap *
  page48_i176
#ISCELL
  mstr_standard tap *
  page48_i177
#ISCELL
  mstr_standard tap *
  page48_i178
#ISCELL
  mstr_standard tap *
  page48_i179
#ISCELL
  mstr_standard tap *
  page48_i180
#ISCELL
  mstr_standard tap *
  page48_i181
#ISCELL
  mstr_standard tap *
  page48_i182
#ISCELL
  mstr_standard tap *
  page48_i183
#ISCELL
  mstr_standard tap *
  page48_i184
#ISCELL
  mstr_standard tap *
  page48_i185
#ISCELL
  mstr_standard tap *
  page48_i186
#ISCELL
  mstr_standard tap *
  page48_i187
#ISCELL
  mstr_standard tap *
  page48_i188
#ISCELL
  mstr_standard tap *
  page48_i189
#ISCELL
  mstr_standard tap *
  page48_i190
#ISCELL
  mstr_standard tap *
  page48_i191
#ISCELL
  mstr_standard tap *
  page48_i192
#ISCELL
  mstr_standard tap *
  page48_i193
#ISCELL
  mstr_standard tap *
  page48_i194
#ISCELL
  mstr_standard offpage *
  page48_i195
#ISCELL
  mstr_standard tap *
  page48_i196
#ISCELL
  mstr_standard tap *
  page48_i197
#ISCELL
  mstr_standard tap *
  page48_i198
#ISCELL
  mstr_standard tap *
  page48_i199
#ISCELL
  mstr_standard tap *
  page48_i200
#ISCELL
  mstr_standard tap *
  page48_i201
#ISCELL
  mstr_standard tap *
  page48_i202
#ISCELL
  mstr_standard tap *
  page48_i203
#ISCELL
  mstr_standard tap *
  page48_i204
#ISCELL
  mstr_standard tap *
  page48_i205
#ISCELL
  mstr_standard tap *
  page48_i206
#ISCELL
  mstr_standard tap *
  page48_i207
#ISCELL
  mstr_standard tap *
  page48_i208
#ISCELL
  mstr_standard tap *
  page48_i209
#ISCELL
  mstr_standard tap *
  page48_i210
#ISCELL
  mstr_standard tap *
  page48_i211
#ISCELL
  mstr_standard tap *
  page48_i212
#ISCELL
  mstr_standard tap *
  page48_i213
#ISCELL
  mstr_standard tap *
  page48_i214
#ISCELL
  mstr_standard tap *
  page48_i215
#ISCELL
  mstr_standard tap *
  page48_i216
#ISCELL
  mstr_standard tap *
  page48_i217
#ISCELL
  mstr_standard tap *
  page48_i218
#ISCELL
  mstr_standard tap *
  page48_i219
#ISCELL
  mstr_standard tap *
  page48_i220
#ISCELL
  mstr_standard tap *
  page48_i221
#ISCELL
  mstr_standard tap *
  page48_i222
#ISCELL
  mstr_standard tap *
  page48_i223
#ISCELL
  mstr_standard tap *
  page48_i224
#ISCELL
  mstr_standard tap *
  page48_i225
#ISCELL
  mstr_standard tap *
  page48_i226
#ISCELL
  mstr_standard tap *
  page48_i227
#ISCELL
  mstr_standard tap *
  page48_i228
#ISCELL
  mstr_standard tap *
  page48_i229
#ISCELL
  mstr_standard tap *
  page48_i230
#ISCELL
  mstr_standard tap *
  page48_i231
#ISCELL
  mstr_standard tap *
  page48_i232
#ISCELL
  mstr_standard offpage *
  page48_i233
#ISCELL
  mstr_standard tap *
  page48_i234
#ISCELL
  mstr_standard tap *
  page48_i235
#ISCELL
  mstr_standard tap *
  page48_i236
#ISCELL
  mstr_standard tap *
  page48_i237
#ISCELL
  mstr_standard tap *
  page48_i238
#ISCELL
  mstr_standard tap *
  page48_i239
#ISCELL
  mstr_standard tap *
  page48_i240
#ISCELL
  mstr_standard tap *
  page48_i241
#ISCELL
  mstr_standard tap *
  page48_i242
#ISCELL
  mstr_standard tap *
  page48_i243
#ISCELL
  mstr_standard tap *
  page48_i244
#ISCELL
  mstr_standard tap *
  page48_i245
#ISCELL
  mstr_standard tap *
  page48_i246
#ISCELL
  mstr_standard tap *
  page48_i247
#ISCELL
  mstr_standard tap *
  page48_i248
#ISCELL
  mstr_standard tap *
  page48_i249
#ISCELL
  mstr_standard tap *
  page48_i250
#ISCELL
  mstr_standard tap *
  page48_i251
#ISCELL
  mstr_standard tap *
  page48_i252
#ISCELL
  mstr_standard tap *
  page48_i253
#ISCELL
  mstr_standard tap *
  page48_i254
#ISCELL
  mstr_standard tap *
  page48_i255
#ISCELL
  mstr_standard tap *
  page48_i256
#ISCELL
  mstr_standard tap *
  page48_i257
#ISCELL
  mstr_standard tap *
  page48_i258
#ISCELL
  mstr_standard tap *
  page48_i259
#ISCELL
  mstr_standard tap *
  page48_i260
#ISCELL
  mstr_standard tap *
  page48_i261
#ISCELL
  mstr_standard tap *
  page48_i262
#ISCELL
  mstr_standard tap *
  page48_i263
#ISCELL
  mstr_standard tap *
  page48_i264
#ISCELL
  mstr_standard tap *
  page48_i265
#ISCELL
  mstr_standard tap *
  page48_i266
#ISCELL
  mstr_standard tap *
  page48_i267
#ISCELL
  mstr_standard tap *
  page48_i268
#ISCELL
  mstr_standard tap *
  page48_i269
#ISCELL
  mstr_standard tap *
  page48_i270
#ISCELL
  mstr_standard tap *
  page48_i271
#ISCELL
  mstr_standard tap *
  page48_i272
#ISCELL
  mstr_standard tap *
  page48_i273
#ISCELL
  mstr_standard tap *
  page48_i274
#ISCELL
  mstr_standard tap *
  page48_i275
#ISCELL
  mstr_standard tap *
  page48_i276
#ISCELL
  mstr_standard tap *
  page48_i277
#ISCELL
  mstr_standard tap *
  page48_i278
#ISCELL
  mstr_standard tap *
  page48_i279
#ISCELL
  standard offpage *
  page48_i280
#ISCELL
  standard offpage *
  page48_i281
#ISCELL
  standard offpage *
  page48_i282
#ISCELL
  standard offpage *
  page48_i283
#ISCELL
  mstr_standard tap *
  page48_i284
#ISCELL
  mstr_standard tap *
  page48_i285
#ISCELL
  mstr_standard tap *
  page48_i286
#ISCELL
  mstr_standard tap *
  page48_i287
#ISCELL
  mstr_standard tap *
  page48_i288
#ISCELL
  mstr_standard tap *
  page48_i289
#ISCELL
  mstr_standard tap *
  page48_i290
#ISCELL
  mstr_standard tap *
  page48_i291
#ISCELL
  mstr_standard tap *
  page48_i292
#ISCELL
  mstr_standard tap *
  page48_i293
#ISCELL
  mstr_standard tap *
  page48_i294
#ISCELL
  mstr_standard tap *
  page48_i295
#ISCELL
  mstr_standard tap *
  page48_i296
#ISCELL
  mstr_standard tap *
  page48_i297
#ISCELL
  mstr_standard tap *
  page48_i298
#ISCELL
  mstr_standard tap *
  page48_i299
#ISCELL
  mstr_standard tap *
  page48_i300
#ISCELL
  mstr_standard tap *
  page48_i301
#ISCELL
  standard offpage *
  page48_i302
#ISCELL
  standard offpage *
  page48_i303
#ISCELL
  standard offpage *
  page48_i304
#ISCELL
  standard offpage *
  page48_i305
#ISCELL
  standard offpage *
  page48_i306
#ISCELL
  standard offpage *
  page48_i307
#ISCELL
  standard offpage *
  page48_i308
#ISCELL
  mstr_standard offpage *
  page48_i309
#ISCELL
  standard offpage *
  page48_i310
#ISCELL
  standard offpage *
  page48_i311
#ISCELL
  standard offpage *
  page48_i312
#CELL
  pure_quanta q_res *
  page48_i313
#ISCELL
  standard offpage *
  page48_i314
#ISCELL
  standard offpage *
  page48_i315
#ISCELL
  mstr_standard offpage *
  page48_i316
